# T6G (Grand Teton) — schematic netlist excerpt (pin names and nets, part order shuffled) for the footprints in the layout excerpt that follows; sources: Cadence DE-HDL packaged netlist, KiCad conversion of 04192023_DAF0TMB3IC0_F0TG_MB_C_brd_V02_OCP.brd

PR3993  Q_RES  0 5% CHIP  pkg 0402LF  page 264 : A = HSC_FLT_TYPE_3 ; B = HSC_FLT_TYPE
PL22  Q_INDUCTOR  90NH/155A IND  pkg SMLF  page 208 : \1\ = SW_PVDD11_S3_P0_SW2 ; \2\ = PVDD11_S3_P0
C5  Q_CAP  0.1UF 25V 10% X7R  pkg 0402  page 124 : A = GPU_3V3IO_RSVD4_ISO ; B = GND

(kicad_pcb
	(version 20260206)
	(generator "pcbnew")
	(generator_version "10.0")
	(general
		(thickness 1.6)
		(legacy_teardrops no)
	)
	(paper "A4")
	(title_block
		(title "04192023_DAF0TMB3IC0_F0TG_MB_C_brd_V02_OCP.brd")
		(comment 1 "Grand Teton / footprints 1743-1745 of 8354")
	)
	(layers
		(0 "F.Cu" signal "TOP")
		(4 "In1.Cu" signal "GND")
		(6 "In2.Cu" signal "IN1")
		(8 "In3.Cu" signal "GND1")
		(10 "In4.Cu" signal "IN2")
		(12 "In5.Cu" signal "GND2")
		(14 "In6.Cu" signal "IN3")
		(16 "In7.Cu" signal "GND3")
		(18 "In8.Cu" signal "VCC")
		(20 "In9.Cu" signal "VCC1")
		(22 "In10.Cu" signal "GND4")
		(24 "In11.Cu" signal "IN4")
		(26 "In12.Cu" signal "GND5")
		(28 "In13.Cu" signal "IN5")
		(30 "In14.Cu" signal "GND6")
		(32 "In15.Cu" signal "IN6")
		(34 "In16.Cu" signal "GND7")
		(2 "B.Cu" signal "BOTTOM")
		(9 "F.Adhes" user "F.Adhesive")
		(11 "B.Adhes" user "B.Adhesive")
		(13 "F.Paste" user "Package Geometry/Pastemask Top")
		(15 "B.Paste" user "Package Geometry/Pastemask Bottom")
		(5 "F.SilkS" user "Ref Des/Silkscreen Top")
		(7 "B.SilkS" user "Ref Des/Silkscreen Bottom")
		(1 "F.Mask" user "Board Geometry/Soldermask Top")
		(3 "B.Mask" user "Board Geometry/Soldermask Bottom")
		(17 "Dwgs.User" user "User.Drawings")
		(19 "Cmts.User" user "User.Comments")
		(21 "Eco1.User" user "User.Eco1")
		(23 "Eco2.User" user "User.Eco2")
		(25 "Edge.Cuts" user "Board Geometry/Outline")
		(27 "Margin" user)
		(31 "F.CrtYd" user "Package Geometry/Place Bound Top")
		(29 "B.CrtYd" user "Package Geometry/Place Bound Bottom")
		(35 "F.Fab" user "Ref Des/Assembly Top")
		(33 "B.Fab" user "Ref Des/Assembly Bottom")
	)
	(footprint ""
		(layer "F.Cu")
		(at 439.072782 -437.34736 -90)
		(property "Reference" "C5"
			(at 0 0 270)
			(layer "F.SilkS")
			(hide yes)
			(effects
				(font
					(size 1.27 1.27)
				)
			)
		)
		(property "Value" ""
			(at 0 0 270)
			(layer "F.Fab")
			(effects
				(font
					(size 1.27 1.27)
				)
			)
		)
		(duplicate_pad_numbers_are_jumpers no)
		(fp_line
			(start -0.7874 0.4064)
			(end -0.7874 -0.4064)
			(stroke
				(width 0.1524)
				(type default)
			)
			(layer "F.SilkS")
		)
		(fp_line
			(start 0.7874 0.4064)
			(end -0.7874 0.4064)
			(stroke
				(width 0.1524)
				(type default)
			)
			(layer "F.SilkS")
		)
		(fp_line
			(start -0.7874 -0.4064)
			(end 0.7874 -0.4064)
			(stroke
				(width 0.1524)
				(type default)
			)
			(layer "F.SilkS")
		)
		(fp_line
			(start 0.7874 -0.4064)
			(end 0.7874 0.4064)
			(stroke
				(width 0.1524)
				(type default)
			)
			(layer "F.SilkS")
		)
		(fp_line
			(start -0.67945 0.3048)
			(end -0.67945 -0.305054)
			(stroke
				(width 0.1)
				(type default)
			)
			(layer "F.Fab")
		)
		(fp_line
			(start -0.12065 0.3048)
			(end -0.67945 0.3048)
			(stroke
				(width 0.1)
				(type default)
			)
			(layer "F.Fab")
		)
		(fp_line
			(start 0.120396 0.3048)
			(end 0.120396 0.2794)
			(stroke
				(width 0.1)
				(type default)
			)
			(layer "F.Fab")
		)
		(fp_line
			(start 0.67945 0.3048)
			(end 0.120396 0.3048)
			(stroke
				(width 0.1)
				(type default)
			)
			(layer "F.Fab")
		)
		(fp_line
			(start -0.12065 0.2794)
			(end -0.12065 0.3048)
			(stroke
				(width 0.1)
				(type default)
			)
			(layer "F.Fab")
		)
		(fp_line
			(start 0.120396 0.2794)
			(end -0.12065 0.2794)
			(stroke
				(width 0.1)
				(type default)
			)
			(layer "F.Fab")
		)
		(fp_line
			(start -0.12065 -0.2794)
			(end 0.12065 -0.2794)
			(stroke
				(width 0.1)
				(type default)
			)
			(layer "F.Fab")
		)
		(fp_line
			(start 0.12065 -0.2794)
			(end 0.12065 -0.3048)
			(stroke
				(width 0.1)
				(type default)
			)
			(layer "F.Fab")
		)
		(fp_line
			(start 0.12065 -0.3048)
			(end 0.67945 -0.3048)
			(stroke
				(width 0.1)
				(type default)
			)
			(layer "F.Fab")
		)
		(fp_line
			(start 0.67945 -0.3048)
			(end 0.67945 0.3048)
			(stroke
				(width 0.1)
				(type default)
			)
			(layer "F.Fab")
		)
		(fp_line
			(start -0.67945 -0.305054)
			(end -0.12065 -0.305054)
			(stroke
				(width 0.1)
				(type default)
			)
			(layer "F.Fab")
		)
		(fp_line
			(start -0.12065 -0.305054)
			(end -0.12065 -0.2794)
			(stroke
				(width 0.1)
				(type default)
			)
			(layer "F.Fab")
		)
		(pad "1" smd circle
			(at -0.40005 0 270)
			(size 0 0)
			(layers "F.Cu" "F.Mask" "F.Paste")
			(net "GPU_3V3IO_RSVD4_ISO")
		)
		(pad "2" smd circle
			(at 0.40005 0 270)
			(size 0 0)
			(layers "F.Cu" "F.Mask" "F.Paste")
			(net "GND")
		)
	)
	(footprint ""
		(layer "F.Cu")
		(at 431.970688 -342.307164 -90)
		(property "Reference" "PL22"
			(at -2.116836 -4.808982 90)
			(unlocked yes)
			(layer "F.SilkS")
			(effects
				(font
					(size 0.7874 0.5842)
					(thickness 0.1524)
				)
				(justify left)
			)
		)
		(property "Value" ""
			(at 0 0 270)
			(layer "F.Fab")
			(effects
				(font
					(size 1.27 1.27)
				)
			)
		)
		(duplicate_pad_numbers_are_jumpers no)
		(fp_line
			(start -4.99999 3.849878)
			(end -4.99999 2.23901)
			(stroke
				(width 0.1524)
				(type default)
			)
			(layer "F.SilkS")
		)
		(fp_line
			(start 4.99999 3.849878)
			(end -4.99999 3.849878)
			(stroke
				(width 0.1524)
				(type default)
			)
			(layer "F.SilkS")
		)
		(fp_line
			(start 4.99999 2.23901)
			(end 4.99999 3.849878)
			(stroke
				(width 0.1524)
				(type default)
			)
			(layer "F.SilkS")
		)
		(fp_line
			(start -4.99999 -2.23901)
			(end -4.99999 -3.849878)
			(stroke
				(width 0.1524)
				(type default)
			)
			(layer "F.SilkS")
		)
		(fp_line
			(start -4.99999 -3.849878)
			(end 4.99999 -3.849878)
			(stroke
				(width 0.1524)
				(type default)
			)
			(layer "F.SilkS")
		)
		(fp_line
			(start 4.99999 -3.849878)
			(end 4.99999 -2.23901)
			(stroke
				(width 0.1524)
				(type default)
			)
			(layer "F.SilkS")
		)
		(fp_line
			(start -4.99999 3.849878)
			(end -4.99999 -3.849878)
			(stroke
				(width 0.1)
				(type default)
			)
			(layer "F.Fab")
		)
		(fp_line
			(start 4.99999 3.849878)
			(end -4.99999 3.849878)
			(stroke
				(width 0.1)
				(type default)
			)
			(layer "F.Fab")
		)
		(fp_line
			(start -4.99999 -3.849878)
			(end 4.99999 -3.849878)
			(stroke
				(width 0.1)
				(type default)
			)
			(layer "F.Fab")
		)
		(fp_line
			(start 4.99999 -3.849878)
			(end 4.99999 3.849878)
			(stroke
				(width 0.1)
				(type default)
			)
			(layer "F.Fab")
		)
		(pad "1" smd rect
			(at -3.299968 0 270)
			(size 3.302 4.2164)
			(layers "F.Cu" "F.Mask" "F.Paste")
			(net "SW_PVDD11_S3_P0_SW2")
		)
		(pad "2" smd rect
			(at 3.299968 0 270)
			(size 3.302 4.2164)
			(layers "F.Cu" "F.Mask" "F.Paste")
			(net "PVDD11_S3_P0")
		)
	)
	(footprint ""
		(layer "F.Cu")
		(at 226.0981 -406.052782)
		(property "Reference" "PR3993"
			(at 0 0 0)
			(layer "F.SilkS")
			(hide yes)
			(effects
				(font
					(size 1.27 1.27)
				)
			)
		)
		(property "Value" ""
			(at 0 0 0)
			(layer "F.Fab")
			(effects
				(font
					(size 1.27 1.27)
				)
			)
		)
		(duplicate_pad_numbers_are_jumpers no)
		(fp_line
			(start -0.7874 -0.4064)
			(end 0.7874 -0.4064)
			(stroke
				(width 0.1524)
				(type default)
			)
			(layer "F.SilkS")
		)
		(fp_line
			(start -0.7874 0.4064)
			(end -0.7874 -0.4064)
			(stroke
				(width 0.1524)
				(type default)
			)
			(layer "F.SilkS")
		)
		(fp_line
			(start 0.7874 -0.4064)
			(end 0.7874 0.4064)
			(stroke
				(width 0.1524)
				(type default)
			)
			(layer "F.SilkS")
		)
		(fp_line
			(start 0.7874 0.4064)
			(end -0.7874 0.4064)
			(stroke
				(width 0.1524)
				(type default)
			)
			(layer "F.SilkS")
		)
		(fp_line
			(start -0.67945 -0.305054)
			(end -0.12065 -0.305054)
			(stroke
				(width 0.1)
				(type default)
			)
			(layer "F.Fab")
		)
		(fp_line
			(start -0.67945 0.3048)
			(end -0.67945 -0.305054)
			(stroke
				(width 0.1)
				(type default)
			)
			(layer "F.Fab")
		)
		(fp_line
			(start -0.12065 -0.305054)
			(end -0.12065 -0.2794)
			(stroke
				(width 0.1)
				(type default)
			)
			(layer "F.Fab")
		)
		(fp_line
			(start -0.12065 -0.2794)
			(end 0.12065 -0.2794)
			(stroke
				(width 0.1)
				(type default)
			)
			(layer "F.Fab")
		)
		(fp_line
			(start -0.12065 0.2794)
			(end -0.12065 0.3048)
			(stroke
				(width 0.1)
				(type default)
			)
			(layer "F.Fab")
		)
		(fp_line
			(start -0.12065 0.3048)
			(end -0.67945 0.3048)
			(stroke
				(width 0.1)
				(type default)
			)
			(layer "F.Fab")
		)
		(fp_line
			(start 0.120396 0.2794)
			(end -0.12065 0.2794)
			(stroke
				(width 0.1)
				(type default)
			)
			(layer "F.Fab")
		)
		(fp_line
			(start 0.120396 0.3048)
			(end 0.120396 0.2794)
			(stroke
				(width 0.1)
				(type default)
			)
			(layer "F.Fab")
		)
		(fp_line
			(start 0.12065 -0.3048)
			(end 0.67945 -0.3048)
			(stroke
				(width 0.1)
				(type default)
			)
			(layer "F.Fab")
		)
		(fp_line
			(start 0.12065 -0.2794)
			(end 0.12065 -0.3048)
			(stroke
				(width 0.1)
				(type default)
			)
			(layer "F.Fab")
		)
		(fp_line
			(start 0.67945 -0.3048)
			(end 0.67945 0.3048)
			(stroke
				(width 0.1)
				(type default)
			)
			(layer "F.Fab")
		)
		(fp_line
			(start 0.67945 0.3048)
			(end 0.120396 0.3048)
			(stroke
				(width 0.1)
				(type default)
			)
			(layer "F.Fab")
		)
		(pad "1" smd circle
			(at -0.40005 0)
			(size 0 0)
			(layers "F.Cu" "F.Mask" "F.Paste")
			(net "HSC_FLT_TYPE_3")
		)
		(pad "2" smd circle
			(at 0.40005 0)
			(size 0 0)
			(layers "F.Cu" "F.Mask" "F.Paste")
			(net "HSC_FLT_TYPE")
		)
	)
)
